(kicad_pcb
	(version 20260206)
	(generator "pcbnew")
	(generator_version "10.0")
	(general
		(thickness 1.6)
		(legacy_teardrops no)
	)
	(paper "A4")
	(title_block
		(title "04192023_DAF0TMB3IC0_F0TG_MB_C_brd_V02_OCP.brd")
		(comment 1 "Grand Teton / footprint 4934 of 8354 (J102), pads 1-113 of 291")
	)
	(layers
		(0 "F.Cu" signal "TOP")
		(4 "In1.Cu" signal "GND")
		(6 "In2.Cu" signal "IN1")
		(8 "In3.Cu" signal "GND1")
		(10 "In4.Cu" signal "IN2")
		(12 "In5.Cu" signal "GND2")
		(14 "In6.Cu" signal "IN3")
		(16 "In7.Cu" signal "GND3")
		(18 "In8.Cu" signal "VCC")
		(20 "In9.Cu" signal "VCC1")
		(22 "In10.Cu" signal "GND4")
		(24 "In11.Cu" signal "IN4")
		(26 "In12.Cu" signal "GND5")
		(28 "In13.Cu" signal "IN5")
		(30 "In14.Cu" signal "GND6")
		(32 "In15.Cu" signal "IN6")
		(34 "In16.Cu" signal "GND7")
		(2 "B.Cu" signal "BOTTOM")
		(9 "F.Adhes" user "F.Adhesive")
		(11 "B.Adhes" user "B.Adhesive")
		(13 "F.Paste" user "Package Geometry/Pastemask Top")
		(15 "B.Paste" user "Package Geometry/Pastemask Bottom")
		(5 "F.SilkS" user "Ref Des/Silkscreen Top")
		(7 "B.SilkS" user "Ref Des/Silkscreen Bottom")
		(1 "F.Mask" user "Board Geometry/Soldermask Top")
		(3 "B.Mask" user "Board Geometry/Soldermask Bottom")
		(17 "Dwgs.User" user "User.Drawings")
		(19 "Cmts.User" user "User.Comments")
		(21 "Eco1.User" user "User.Eco1")
		(23 "Eco2.User" user "User.Eco2")
		(25 "Edge.Cuts" user "Board Geometry/Outline")
		(27 "Margin" user)
		(31 "F.CrtYd" user "Package Geometry/Place Bound Top")
		(29 "B.CrtYd" user "Package Geometry/Place Bound Bottom")
		(35 "F.Fab" user "Ref Des/Assembly Top")
		(33 "B.Fab" user "Ref Des/Assembly Bottom")
	)
	(footprint ""
		(layer "F.Cu")
		(at 166.47795 -255.560322 180)
		(property "Reference" "J102"
			(at -2.7178 -81.857088 0)
			(unlocked yes)
			(layer "F.SilkS")
			(effects
				(font
					(size 0.7874 0.5842)
					(thickness 0.1524)
				)
			)
		)
		(property "Value" ""
			(at 0 0 180)
			(layer "F.Fab")
			(effects
				(font
					(size 1.27 1.27)
				)
			)
		)
		(duplicate_pad_numbers_are_jumpers no)
		(pad "1" smd rect
			(at -2.050034 -63.324994 90)
			(size 0.519938 1.4986)
			(layers "F.Cu" "F.Mask" "F.Paste")
			(net "P12V_MEM_CPU1")
		)
		(pad "2" smd rect
			(at -2.050034 -62.47511 90)
			(size 0.519938 1.4986)
			(layers "F.Cu" "F.Mask" "F.Paste")
			(net "Net_2340")
		)
		(pad "3" smd rect
			(at -2.050034 -61.624972 90)
			(size 0.519938 1.4986)
			(layers "F.Cu" "F.Mask" "F.Paste")
			(net "P3V3_AUX")
		)
		(pad "4" smd rect
			(at -2.050034 -60.775088 90)
			(size 0.519938 1.4986)
			(layers "F.Cu" "F.Mask" "F.Paste")
			(net "I3C_SPD_DDRG_CPU1_SCL")
		)
		(pad "5" smd rect
			(at -2.050034 -59.92495 90)
			(size 0.519938 1.4986)
			(layers "F.Cu" "F.Mask" "F.Paste")
			(net "I3C_SPD_DDRG_CPU1_SDA")
		)
		(pad "6" smd rect
			(at -2.050034 -59.075066 90)
			(size 0.519938 1.4986)
			(layers "F.Cu" "F.Mask" "F.Paste")
			(net "GND")
		)
		(pad "7" smd rect
			(at -2.050034 -58.224928 90)
			(size 0.519938 1.4986)
			(layers "F.Cu" "F.Mask" "F.Paste")
			(net "M_G_CPU1_SA_DQ<0>")
		)
		(pad "8" smd rect
			(at -2.050034 -57.375044 90)
			(size 0.519938 1.4986)
			(layers "F.Cu" "F.Mask" "F.Paste")
			(net "GND")
		)
		(pad "9" smd rect
			(at -2.050034 -56.524906 90)
			(size 0.519938 1.4986)
			(layers "F.Cu" "F.Mask" "F.Paste")
			(net "M_G_CPU1_SA_DQ<1>")
		)
		(pad "10" smd rect
			(at -2.050034 -55.675022 90)
			(size 0.519938 1.4986)
			(layers "F.Cu" "F.Mask" "F.Paste")
			(net "GND")
		)
		(pad "11" smd rect
			(at -2.050034 -54.824884 90)
			(size 0.519938 1.4986)
			(layers "F.Cu" "F.Mask" "F.Paste")
			(net "M_G_CPU1_SA_DQS_DP<0>")
		)
		(pad "12" smd rect
			(at -2.050034 -53.975 90)
			(size 0.519938 1.4986)
			(layers "F.Cu" "F.Mask" "F.Paste")
			(net "M_G_CPU1_SA_DQS_DN<0>")
		)
		(pad "13" smd rect
			(at -2.050034 -53.125116 90)
			(size 0.519938 1.4986)
			(layers "F.Cu" "F.Mask" "F.Paste")
			(net "GND")
		)
		(pad "14" smd rect
			(at -2.050034 -52.274978 90)
			(size 0.519938 1.4986)
			(layers "F.Cu" "F.Mask" "F.Paste")
			(net "M_G_CPU1_SA_DQ<4>")
		)
		(pad "15" smd rect
			(at -2.050034 -51.425094 90)
			(size 0.519938 1.4986)
			(layers "F.Cu" "F.Mask" "F.Paste")
			(net "GND")
		)
		(pad "16" smd rect
			(at -2.050034 -50.574956 90)
			(size 0.519938 1.4986)
			(layers "F.Cu" "F.Mask" "F.Paste")
			(net "M_G_CPU1_SA_DQ<5>")
		)
		(pad "17" smd rect
			(at -2.050034 -49.725072 90)
			(size 0.519938 1.4986)
			(layers "F.Cu" "F.Mask" "F.Paste")
			(net "GND")
		)
		(pad "18" smd rect
			(at -2.050034 -48.874934 90)
			(size 0.519938 1.4986)
			(layers "F.Cu" "F.Mask" "F.Paste")
			(net "M_G_CPU1_SA_DQ<8>")
		)
		(pad "19" smd rect
			(at -2.050034 -48.02505 90)
			(size 0.519938 1.4986)
			(layers "F.Cu" "F.Mask" "F.Paste")
			(net "GND")
		)
		(pad "20" smd rect
			(at -2.050034 -47.174912 90)
			(size 0.519938 1.4986)
			(layers "F.Cu" "F.Mask" "F.Paste")
			(net "M_G_CPU1_SA_DQ<9>")
		)
		(pad "21" smd rect
			(at -2.050034 -46.325028 90)
			(size 0.519938 1.4986)
			(layers "F.Cu" "F.Mask" "F.Paste")
			(net "GND")
		)
		(pad "22" smd rect
			(at -2.050034 -45.47489 90)
			(size 0.519938 1.4986)
			(layers "F.Cu" "F.Mask" "F.Paste")
			(net "M_G_CPU1_SA_DQS_DP<1>")
		)
		(pad "23" smd rect
			(at -2.050034 -44.625006 90)
			(size 0.519938 1.4986)
			(layers "F.Cu" "F.Mask" "F.Paste")
			(net "M_G_CPU1_SA_DQS_DN<1>")
		)
		(pad "24" smd rect
			(at -2.050034 -43.775122 90)
			(size 0.519938 1.4986)
			(layers "F.Cu" "F.Mask" "F.Paste")
			(net "GND")
		)
		(pad "25" smd rect
			(at -2.050034 -42.924984 90)
			(size 0.519938 1.4986)
			(layers "F.Cu" "F.Mask" "F.Paste")
			(net "M_G_CPU1_SA_DQ<12>")
		)
		(pad "26" smd rect
			(at -2.050034 -42.0751 90)
			(size 0.519938 1.4986)
			(layers "F.Cu" "F.Mask" "F.Paste")
			(net "GND")
		)
		(pad "27" smd rect
			(at -2.050034 -41.224962 90)
			(size 0.519938 1.4986)
			(layers "F.Cu" "F.Mask" "F.Paste")
			(net "M_G_CPU1_SA_DQ<13>")
		)
		(pad "28" smd rect
			(at -2.050034 -40.375078 90)
			(size 0.519938 1.4986)
			(layers "F.Cu" "F.Mask" "F.Paste")
			(net "GND")
		)
		(pad "29" smd rect
			(at -2.050034 -39.52494 90)
			(size 0.519938 1.4986)
			(layers "F.Cu" "F.Mask" "F.Paste")
			(net "M_G_CPU1_SA_DQ<16>")
		)
		(pad "30" smd rect
			(at -2.050034 -38.675056 90)
			(size 0.519938 1.4986)
			(layers "F.Cu" "F.Mask" "F.Paste")
			(net "GND")
		)
		(pad "31" smd rect
			(at -2.050034 -37.824918 90)
			(size 0.519938 1.4986)
			(layers "F.Cu" "F.Mask" "F.Paste")
			(net "M_G_CPU1_SA_DQ<17>")
		)
		(pad "32" smd rect
			(at -2.050034 -36.975034 90)
			(size 0.519938 1.4986)
			(layers "F.Cu" "F.Mask" "F.Paste")
			(net "GND")
		)
		(pad "33" smd rect
			(at -2.050034 -36.124896 90)
			(size 0.519938 1.4986)
			(layers "F.Cu" "F.Mask" "F.Paste")
			(net "M_G_CPU1_SA_DQS_DP<2>")
		)
		(pad "34" smd rect
			(at -2.050034 -35.275012 90)
			(size 0.519938 1.4986)
			(layers "F.Cu" "F.Mask" "F.Paste")
			(net "M_G_CPU1_SA_DQS_DN<2>")
		)
		(pad "35" smd rect
			(at -2.050034 -34.425128 90)
			(size 0.519938 1.4986)
			(layers "F.Cu" "F.Mask" "F.Paste")
			(net "GND")
		)
		(pad "36" smd rect
			(at -2.050034 -33.57499 90)
			(size 0.519938 1.4986)
			(layers "F.Cu" "F.Mask" "F.Paste")
			(net "M_G_CPU1_SA_DQ<20>")
		)
		(pad "37" smd rect
			(at -2.050034 -32.725106 90)
			(size 0.519938 1.4986)
			(layers "F.Cu" "F.Mask" "F.Paste")
			(net "GND")
		)
		(pad "38" smd rect
			(at -2.050034 -31.874968 90)
			(size 0.519938 1.4986)
			(layers "F.Cu" "F.Mask" "F.Paste")
			(net "M_G_CPU1_SA_DQ<21>")
		)
		(pad "39" smd rect
			(at -2.050034 -31.025084 90)
			(size 0.519938 1.4986)
			(layers "F.Cu" "F.Mask" "F.Paste")
			(net "GND")
		)
		(pad "40" smd rect
			(at -2.050034 -30.174946 90)
			(size 0.519938 1.4986)
			(layers "F.Cu" "F.Mask" "F.Paste")
			(net "M_G_CPU1_SA_DQ<24>")
		)
		(pad "41" smd rect
			(at -2.050034 -29.325062 90)
			(size 0.519938 1.4986)
			(layers "F.Cu" "F.Mask" "F.Paste")
			(net "GND")
		)
		(pad "42" smd rect
			(at -2.050034 -28.474924 90)
			(size 0.519938 1.4986)
			(layers "F.Cu" "F.Mask" "F.Paste")
			(net "M_G_CPU1_SA_DQ<25>")
		)
		(pad "43" smd rect
			(at -2.050034 -27.62504 90)
			(size 0.519938 1.4986)
			(layers "F.Cu" "F.Mask" "F.Paste")
			(net "GND")
		)
		(pad "44" smd rect
			(at -2.050034 -26.774902 90)
			(size 0.519938 1.4986)
			(layers "F.Cu" "F.Mask" "F.Paste")
			(net "M_G_CPU1_SA_DQS_DP<3>")
		)
		(pad "45" smd rect
			(at -2.050034 -25.925018 90)
			(size 0.519938 1.4986)
			(layers "F.Cu" "F.Mask" "F.Paste")
			(net "M_G_CPU1_SA_DQS_DN<3>")
		)
		(pad "46" smd rect
			(at -2.050034 -25.07488 90)
			(size 0.519938 1.4986)
			(layers "F.Cu" "F.Mask" "F.Paste")
			(net "GND")
		)
		(pad "47" smd rect
			(at -2.050034 -24.224996 90)
			(size 0.519938 1.4986)
			(layers "F.Cu" "F.Mask" "F.Paste")
			(net "M_G_CPU1_SA_DQ<28>")
		)
		(pad "48" smd rect
			(at -2.050034 -23.375112 90)
			(size 0.519938 1.4986)
			(layers "F.Cu" "F.Mask" "F.Paste")
			(net "GND")
		)
		(pad "49" smd rect
			(at -2.050034 -22.524974 90)
			(size 0.519938 1.4986)
			(layers "F.Cu" "F.Mask" "F.Paste")
			(net "M_G_CPU1_SA_DQ<29>")
		)
		(pad "50" smd rect
			(at -2.050034 -21.67509 90)
			(size 0.519938 1.4986)
			(layers "F.Cu" "F.Mask" "F.Paste")
			(net "GND")
		)
		(pad "51" smd rect
			(at -2.050034 -20.824952 90)
			(size 0.519938 1.4986)
			(layers "F.Cu" "F.Mask" "F.Paste")
			(net "M_G_CPU1_SA_CB<0>")
		)
		(pad "52" smd rect
			(at -2.050034 -19.975068 90)
			(size 0.519938 1.4986)
			(layers "F.Cu" "F.Mask" "F.Paste")
			(net "GND")
		)
		(pad "53" smd rect
			(at -2.050034 -19.12493 90)
			(size 0.519938 1.4986)
			(layers "F.Cu" "F.Mask" "F.Paste")
			(net "M_G_CPU1_SA_CB<1>")
		)
		(pad "54" smd rect
			(at -2.050034 -18.275046 90)
			(size 0.519938 1.4986)
			(layers "F.Cu" "F.Mask" "F.Paste")
			(net "GND")
		)
		(pad "55" smd rect
			(at -2.050034 -17.424908 90)
			(size 0.519938 1.4986)
			(layers "F.Cu" "F.Mask" "F.Paste")
			(net "M_G_CPU1_SA_DQS_DP<4>")
		)
		(pad "56" smd rect
			(at -2.050034 -16.575024 90)
			(size 0.519938 1.4986)
			(layers "F.Cu" "F.Mask" "F.Paste")
			(net "M_G_CPU1_SA_DQS_DN<4>")
		)
		(pad "57" smd rect
			(at -2.050034 -15.724886 90)
			(size 0.519938 1.4986)
			(layers "F.Cu" "F.Mask" "F.Paste")
			(net "GND")
		)
		(pad "58" smd rect
			(at -2.050034 -14.875002 90)
			(size 0.519938 1.4986)
			(layers "F.Cu" "F.Mask" "F.Paste")
			(net "M_G_CPU1_SA_CB<4>")
		)
		(pad "59" smd rect
			(at -2.050034 -14.025118 90)
			(size 0.519938 1.4986)
			(layers "F.Cu" "F.Mask" "F.Paste")
			(net "GND")
		)
		(pad "60" smd rect
			(at -2.050034 -13.17498 90)
			(size 0.519938 1.4986)
			(layers "F.Cu" "F.Mask" "F.Paste")
			(net "M_G_CPU1_SA_CB<5>")
		)
		(pad "61" smd rect
			(at -2.050034 -12.325096 90)
			(size 0.519938 1.4986)
			(layers "F.Cu" "F.Mask" "F.Paste")
			(net "GND")
		)
		(pad "62" smd rect
			(at -2.050034 -11.474958 90)
			(size 0.519938 1.4986)
			(layers "F.Cu" "F.Mask" "F.Paste")
			(net "M_G_CPU1_ALERT_N")
		)
		(pad "63" smd rect
			(at -2.050034 -10.625074 90)
			(size 0.519938 1.4986)
			(layers "F.Cu" "F.Mask" "F.Paste")
			(net "GND")
		)
		(pad "64" smd rect
			(at -2.050034 -9.774936 90)
			(size 0.519938 1.4986)
			(layers "F.Cu" "F.Mask" "F.Paste")
			(net "M_G_CPU1_SA_CS_N<0>")
		)
		(pad "65" smd rect
			(at -2.050034 -8.925052 90)
			(size 0.519938 1.4986)
			(layers "F.Cu" "F.Mask" "F.Paste")
			(net "GND")
		)
		(pad "66" smd rect
			(at -2.050034 -8.074914 90)
			(size 0.519938 1.4986)
			(layers "F.Cu" "F.Mask" "F.Paste")
			(net "M_G_CPU1_SA_CA<0>")
		)
		(pad "67" smd rect
			(at -2.050034 -7.22503 90)
			(size 0.519938 1.4986)
			(layers "F.Cu" "F.Mask" "F.Paste")
			(net "GND")
		)
		(pad "68" smd rect
			(at -2.050034 -6.374892 90)
			(size 0.519938 1.4986)
			(layers "F.Cu" "F.Mask" "F.Paste")
			(net "M_G_CPU1_SA_CA<2>")
		)
		(pad "69" smd rect
			(at -2.050034 -5.525008 90)
			(size 0.519938 1.4986)
			(layers "F.Cu" "F.Mask" "F.Paste")
			(net "GND")
		)
		(pad "70" smd rect
			(at -2.050034 -4.675124 90)
			(size 0.519938 1.4986)
			(layers "F.Cu" "F.Mask" "F.Paste")
			(net "M_G_CPU1_SA_CA<4>")
		)
		(pad "71" smd rect
			(at -2.050034 -3.824986 90)
			(size 0.519938 1.4986)
			(layers "F.Cu" "F.Mask" "F.Paste")
			(net "GND")
		)
		(pad "72" smd rect
			(at -2.050034 -2.975102 90)
			(size 0.519938 1.4986)
			(layers "F.Cu" "F.Mask" "F.Paste")
			(net "M_G_CPU1_SA_CA<6>")
		)
		(pad "73" smd rect
			(at -2.050034 -2.124964 90)
			(size 0.519938 1.4986)
			(layers "F.Cu" "F.Mask" "F.Paste")
			(net "GND")
		)
		(pad "74" smd rect
			(at -2.050034 -1.27508 90)
			(size 0.519938 1.4986)
			(layers "F.Cu" "F.Mask" "F.Paste")
			(net "M_G_CPU1_SA_PAR")
		)
		(pad "75" smd rect
			(at -2.050034 -0.424942 90)
			(size 0.519938 1.4986)
			(layers "F.Cu" "F.Mask" "F.Paste")
			(net "GND")
		)
		(pad "76" smd rect
			(at -2.050034 5.525008 90)
			(size 0.519938 1.4986)
			(layers "F.Cu" "F.Mask" "F.Paste")
			(net "M_G_CPU1_SB_CA<0>")
		)
		(pad "77" smd rect
			(at -2.050034 6.374892 90)
			(size 0.519938 1.4986)
			(layers "F.Cu" "F.Mask" "F.Paste")
			(net "GND")
		)
		(pad "78" smd rect
			(at -2.050034 7.22503 90)
			(size 0.519938 1.4986)
			(layers "F.Cu" "F.Mask" "F.Paste")
			(net "M_G_CPU1_SB_CA<2>")
		)
		(pad "79" smd rect
			(at -2.050034 8.074914 90)
			(size 0.519938 1.4986)
			(layers "F.Cu" "F.Mask" "F.Paste")
			(net "GND")
		)
		(pad "80" smd rect
			(at -2.050034 8.925052 90)
			(size 0.519938 1.4986)
			(layers "F.Cu" "F.Mask" "F.Paste")
			(net "M_G_CPU1_SB_CA<4>")
		)
		(pad "81" smd rect
			(at -2.050034 9.774936 90)
			(size 0.519938 1.4986)
			(layers "F.Cu" "F.Mask" "F.Paste")
			(net "GND")
		)
		(pad "82" smd rect
			(at -2.050034 10.625074 90)
			(size 0.519938 1.4986)
			(layers "F.Cu" "F.Mask" "F.Paste")
			(net "M_G_CPU1_SB_CA<6>")
		)
		(pad "83" smd rect
			(at -2.050034 11.474958 90)
			(size 0.519938 1.4986)
			(layers "F.Cu" "F.Mask" "F.Paste")
			(net "GND")
		)
		(pad "84" smd rect
			(at -2.050034 12.325096 90)
			(size 0.519938 1.4986)
			(layers "F.Cu" "F.Mask" "F.Paste")
			(net "M_G_CPU1_SB_CS_N<0>")
		)
		(pad "85" smd rect
			(at -2.050034 13.17498 90)
			(size 0.519938 1.4986)
			(layers "F.Cu" "F.Mask" "F.Paste")
			(net "GND")
		)
		(pad "86" smd rect
			(at -2.050034 14.025118 90)
			(size 0.519938 1.4986)
			(layers "F.Cu" "F.Mask" "F.Paste")
			(net "M_G_CPU1_SA_RSP<0>")
		)
		(pad "87" smd rect
			(at -2.050034 14.875002 90)
			(size 0.519938 1.4986)
			(layers "F.Cu" "F.Mask" "F.Paste")
			(net "M_G_CPU1_SB_RSP<0>")
		)
		(pad "88" smd rect
			(at -2.050034 15.724886 90)
			(size 0.519938 1.4986)
			(layers "F.Cu" "F.Mask" "F.Paste")
			(net "GND")
		)
		(pad "89" smd rect
			(at -2.050034 16.575024 90)
			(size 0.519938 1.4986)
			(layers "F.Cu" "F.Mask" "F.Paste")
			(net "M_G_CPU1_SB_CB<4>")
		)
		(pad "90" smd rect
			(at -2.050034 17.424908 90)
			(size 0.519938 1.4986)
			(layers "F.Cu" "F.Mask" "F.Paste")
			(net "GND")
		)
		(pad "91" smd rect
			(at -2.050034 18.275046 90)
			(size 0.519938 1.4986)
			(layers "F.Cu" "F.Mask" "F.Paste")
			(net "M_G_CPU1_SB_CB<5>")
		)
		(pad "92" smd rect
			(at -2.050034 19.12493 90)
			(size 0.519938 1.4986)
			(layers "F.Cu" "F.Mask" "F.Paste")
			(net "GND")
		)
		(pad "93" smd rect
			(at -2.050034 19.975068 90)
			(size 0.519938 1.4986)
			(layers "F.Cu" "F.Mask" "F.Paste")
			(net "M_G_CPU1_SB_DQS_DP<9>")
		)
		(pad "94" smd rect
			(at -2.050034 20.824952 90)
			(size 0.519938 1.4986)
			(layers "F.Cu" "F.Mask" "F.Paste")
			(net "M_G_CPU1_SB_DQS_DN<9>")
		)
		(pad "95" smd rect
			(at -2.050034 21.67509 90)
			(size 0.519938 1.4986)
			(layers "F.Cu" "F.Mask" "F.Paste")
			(net "GND")
		)
		(pad "96" smd rect
			(at -2.050034 22.524974 90)
			(size 0.519938 1.4986)
			(layers "F.Cu" "F.Mask" "F.Paste")
			(net "M_G_CPU1_SB_CB<0>")
		)
		(pad "97" smd rect
			(at -2.050034 23.375112 90)
			(size 0.519938 1.4986)
			(layers "F.Cu" "F.Mask" "F.Paste")
			(net "GND")
		)
		(pad "98" smd rect
			(at -2.050034 24.224996 90)
			(size 0.519938 1.4986)
			(layers "F.Cu" "F.Mask" "F.Paste")
			(net "M_G_CPU1_SB_CB<1>")
		)
		(pad "99" smd rect
			(at -2.050034 25.07488 90)
			(size 0.519938 1.4986)
			(layers "F.Cu" "F.Mask" "F.Paste")
			(net "GND")
		)
		(pad "100" smd rect
			(at -2.050034 25.925018 90)
			(size 0.519938 1.4986)
			(layers "F.Cu" "F.Mask" "F.Paste")
			(net "M_G_CPU1_SB_DQ<0>")
		)
		(pad "101" smd rect
			(at -2.050034 26.774902 90)
			(size 0.519938 1.4986)
			(layers "F.Cu" "F.Mask" "F.Paste")
			(net "GND")
		)
		(pad "102" smd rect
			(at -2.050034 27.62504 90)
			(size 0.519938 1.4986)
			(layers "F.Cu" "F.Mask" "F.Paste")
			(net "M_G_CPU1_SB_DQ<1>")
		)
		(pad "103" smd rect
			(at -2.050034 28.474924 90)
			(size 0.519938 1.4986)
			(layers "F.Cu" "F.Mask" "F.Paste")
			(net "GND")
		)
		(pad "104" smd rect
			(at -2.050034 29.325062 90)
			(size 0.519938 1.4986)
			(layers "F.Cu" "F.Mask" "F.Paste")
			(net "M_G_CPU1_SB_DQS_DP<0>")
		)
		(pad "105" smd rect
			(at -2.050034 30.174946 90)
			(size 0.519938 1.4986)
			(layers "F.Cu" "F.Mask" "F.Paste")
			(net "M_G_CPU1_SB_DQS_DN<0>")
		)
		(pad "106" smd rect
			(at -2.050034 31.025084 90)
			(size 0.519938 1.4986)
			(layers "F.Cu" "F.Mask" "F.Paste")
			(net "GND")
		)
		(pad "107" smd rect
			(at -2.050034 31.874968 90)
			(size 0.519938 1.4986)
			(layers "F.Cu" "F.Mask" "F.Paste")
			(net "M_G_CPU1_SB_DQ<4>")
		)
		(pad "108" smd rect
			(at -2.050034 32.725106 90)
			(size 0.519938 1.4986)
			(layers "F.Cu" "F.Mask" "F.Paste")
			(net "GND")
		)
		(pad "109" smd rect
			(at -2.050034 33.57499 90)
			(size 0.519938 1.4986)
			(layers "F.Cu" "F.Mask" "F.Paste")
			(net "M_G_CPU1_SB_DQ<5>")
		)
		(pad "110" smd rect
			(at -2.050034 34.425128 90)
			(size 0.519938 1.4986)
			(layers "F.Cu" "F.Mask" "F.Paste")
			(net "GND")
		)
		(pad "111" smd rect
			(at -2.050034 35.275012 90)
			(size 0.519938 1.4986)
			(layers "F.Cu" "F.Mask" "F.Paste")
			(net "M_G_CPU1_SB_DQ<8>")
		)
		(pad "112" smd rect
			(at -2.050034 36.124896 90)
			(size 0.519938 1.4986)
			(layers "F.Cu" "F.Mask" "F.Paste")
			(net "GND")
		)
		(pad "113" smd rect
			(at -2.050034 36.975034 90)
			(size 0.519938 1.4986)
			(layers "F.Cu" "F.Mask" "F.Paste")
			(net "M_G_CPU1_SB_DQ<9>")
		)
	)
)
